# BASEBOARD_FAB2 (Tioga Pass) — schematic netlist excerpt (pin names and nets, part order shuffled) for the footprints in the layout excerpt that follows; sources: Cadence DE-HDL packaged netlist, KiCad conversion of Wiwynn_Tioga_Pass_MB.brd

C4A14  CAP  1.0UF 16V 10% X6S  pkg 0402  page 230 : A = VR_PVTT_KLM_VREF ; B = GND
C4E27  CAP  0.22UF 16V 10% X7R  pkg 0402  page 202 : A = P5V_STBY ; B = GND
C7C10  CAP_A  22.0UF 4V 20% X6S  pkg 0603V  page 212 : A = PVCCIO_CPU0 ; B = GND

(kicad_pcb
	(version 20260206)
	(generator "pcbnew")
	(generator_version "10.0")
	(general
		(thickness 1.6)
		(legacy_teardrops no)
	)
	(paper "A4")
	(title_block
		(title "Wiwynn_Tioga_Pass_MB.brd")
		(comment 1 "Tioga Pass / footprints 774-776 of 4770")
	)
	(layers
		(0 "F.Cu" signal "TOP")
		(4 "In1.Cu" signal "L2GND")
		(6 "In2.Cu" signal "L3")
		(8 "In3.Cu" signal "L4GND")
		(10 "In4.Cu" signal "L5")
		(12 "In5.Cu" signal "L6GND")
		(14 "In6.Cu" signal "L7VCC")
		(16 "In7.Cu" signal "L8VCC")
		(18 "In8.Cu" signal "L9GND")
		(20 "In9.Cu" signal "L10")
		(22 "In10.Cu" signal "L11GND")
		(24 "In11.Cu" signal "L12")
		(26 "In12.Cu" signal "L13GND")
		(2 "B.Cu" signal "BOTTOM")
		(9 "F.Adhes" user "F.Adhesive")
		(11 "B.Adhes" user "B.Adhesive")
		(13 "F.Paste" user "Package Geometry/Pastemask Top")
		(15 "B.Paste" user "Package Geometry/Pastemask Bottom")
		(5 "F.SilkS" user "Ref Des/Silkscreen Top")
		(7 "B.SilkS" user "Ref Des/Silkscreen Bottom")
		(1 "F.Mask" user "Board Geometry/Soldermask Top")
		(3 "B.Mask" user "Board Geometry/Soldermask Bottom")
		(17 "Dwgs.User" user "User.Drawings")
		(19 "Cmts.User" user "User.Comments")
		(21 "Eco1.User" user "User.Eco1")
		(23 "Eco2.User" user "User.Eco2")
		(25 "Edge.Cuts" user "Board Geometry/Outline")
		(27 "Margin" user)
		(31 "F.CrtYd" user "Package Geometry/Place Bound Top")
		(29 "B.CrtYd" user "Package Geometry/Place Bound Bottom")
		(35 "F.Fab" user "Ref Des/Assembly Top")
		(33 "B.Fab" user "Ref Des/Assembly Bottom")
	)
	(footprint ""
		(layer "F.Cu")
		(at 173.507146 -145.667222 90)
		(property "Reference" "C4A14"
			(at 0 0 90)
			(layer "F.SilkS")
			(hide yes)
			(effects
				(font
					(size 1.27 1.27)
				)
			)
		)
		(property "Value" ""
			(at 0 0 90)
			(layer "F.Fab")
			(effects
				(font
					(size 1.27 1.27)
				)
			)
		)
		(duplicate_pad_numbers_are_jumpers no)
		(fp_rect
			(start 0.3048 0.9906)
			(end -0.3048 -0.1016)
			(stroke
				(width 0)
				(type default)
			)
			(fill no)
			(layer "F.CrtYd")
		)
		(fp_line
			(start 0.3048 -0.1016)
			(end -0.3048 -0.1016)
			(stroke
				(width 0.1)
				(type default)
			)
			(layer "F.Fab")
		)
		(fp_line
			(start -0.3048 -0.1016)
			(end -0.3048 0.9906)
			(stroke
				(width 0.1)
				(type default)
			)
			(layer "F.Fab")
		)
		(fp_line
			(start 0.3048 0.9906)
			(end 0.3048 -0.1016)
			(stroke
				(width 0.1)
				(type default)
			)
			(layer "F.Fab")
		)
		(fp_line
			(start -0.3048 0.9906)
			(end 0.3048 0.9906)
			(stroke
				(width 0.1)
				(type default)
			)
			(layer "F.Fab")
		)
		(pad "1" smd rect
			(at 0 0 90)
			(size 0.508 0.508)
			(layers "F.Cu" "F.Mask" "F.Paste")
			(net "VR_PVTT_KLM_VREF")
		)
		(pad "2" smd rect
			(at 0 0.889 90)
			(size 0.508 0.508)
			(layers "F.Cu" "F.Mask" "F.Paste")
			(net "GND")
		)
		(zone
			(layer "F.Cu")
			(hatch none 0.5)
			(connect_pads
				(clearance 0)
			)
			(min_thickness 0.25)
			(keepout
				(tracks allowed)
				(vias not_allowed)
				(pads allowed)
				(copperpour not_allowed)
				(footprints allowed)
			)
			(placement
				(enabled no)
				(sheetname "")
			)
			(fill
				(thermal_gap 0.5)
				(thermal_bridge_width 0.5)
				(island_removal_mode 0)
			)
			(polygon
				(pts
					(xy 174.142146 -145.921222) (xy 173.761146 -145.921222) (xy 173.761146 -145.413222) (xy 174.142146 -145.413222)
				)
			)
		)
		(zone
			(layer "F.Cu")
			(hatch none 0.5)
			(connect_pads
				(clearance 0)
			)
			(min_thickness 0.25)
			(keepout
				(tracks not_allowed)
				(vias allowed)
				(pads allowed)
				(copperpour not_allowed)
				(footprints allowed)
			)
			(placement
				(enabled no)
				(sheetname "")
			)
			(fill
				(thermal_gap 0.5)
				(thermal_bridge_width 0.5)
				(island_removal_mode 0)
			)
			(polygon
				(pts
					(xy 174.142146 -145.921222) (xy 173.761146 -145.921222) (xy 173.761146 -145.413222) (xy 174.142146 -145.413222)
				)
			)
		)
	)
	(footprint ""
		(layer "F.Cu")
		(at 339.3948 -102.6922 90)
		(property "Reference" "C7C10"
			(at 0 0 90)
			(layer "F.SilkS")
			(hide yes)
			(effects
				(font
					(size 1.27 1.27)
				)
			)
		)
		(property "Value" ""
			(at 0 0 90)
			(layer "F.Fab")
			(effects
				(font
					(size 1.27 1.27)
				)
			)
		)
		(duplicate_pad_numbers_are_jumpers no)
		(fp_poly
			(pts
				(xy -0.4953 -0.2032) (xy 0.4953 -0.2032) (xy 0.4953 1.6002) (xy -0.4953 1.6002)
			)
			(stroke
				(width 0)
				(type default)
			)
			(fill no)
			(layer "F.CrtYd")
		)
		(fp_line
			(start 0.4953 -0.2032)
			(end 0.4953 1.6002)
			(stroke
				(width 0.1)
				(type default)
			)
			(layer "F.Fab")
		)
		(fp_line
			(start -0.4953 -0.2032)
			(end 0.4953 -0.2032)
			(stroke
				(width 0.1)
				(type default)
			)
			(layer "F.Fab")
		)
		(fp_line
			(start 0.4953 1.6002)
			(end -0.4953 1.6002)
			(stroke
				(width 0.1)
				(type default)
			)
			(layer "F.Fab")
		)
		(fp_line
			(start -0.4953 1.6002)
			(end -0.4953 -0.2032)
			(stroke
				(width 0.1)
				(type default)
			)
			(layer "F.Fab")
		)
		(pad "1" smd rect
			(at 0 0 90)
			(size 0.762 0.889)
			(layers "F.Cu" "F.Mask" "F.Paste")
			(net "PVCCIO_CPU0")
		)
		(pad "2" smd rect
			(at 0 1.397 90)
			(size 0.762 0.889)
			(layers "F.Cu" "F.Mask" "F.Paste")
			(net "GND")
		)
		(zone
			(layer "F.Cu")
			(hatch none 0.5)
			(connect_pads
				(clearance 0)
			)
			(min_thickness 0.25)
			(keepout
				(tracks not_allowed)
				(vias allowed)
				(pads allowed)
				(copperpour not_allowed)
				(footprints allowed)
			)
			(placement
				(enabled no)
				(sheetname "")
			)
			(fill
				(thermal_gap 0.5)
				(thermal_bridge_width 0.5)
				(island_removal_mode 0)
			)
			(polygon
				(pts
					(xy 339.8393 -102.3112) (xy 339.8393 -103.0732) (xy 340.3473 -103.0732) (xy 340.3473 -102.3112)
				)
			)
		)
	)
	(footprint ""
		(layer "F.Cu")
		(at 198.11619 -61.118242 90)
		(property "Reference" "C4E27"
			(at 0 0 90)
			(layer "F.SilkS")
			(hide yes)
			(effects
				(font
					(size 1.27 1.27)
				)
			)
		)
		(property "Value" ""
			(at 0 0 90)
			(layer "F.Fab")
			(effects
				(font
					(size 1.27 1.27)
				)
			)
		)
		(duplicate_pad_numbers_are_jumpers no)
		(fp_rect
			(start 0.3048 0.9906)
			(end -0.3048 -0.1016)
			(stroke
				(width 0)
				(type default)
			)
			(fill no)
			(layer "F.CrtYd")
		)
		(fp_line
			(start 0.3048 -0.1016)
			(end -0.3048 -0.1016)
			(stroke
				(width 0.1)
				(type default)
			)
			(layer "F.Fab")
		)
		(fp_line
			(start -0.3048 -0.1016)
			(end -0.3048 0.9906)
			(stroke
				(width 0.1)
				(type default)
			)
			(layer "F.Fab")
		)
		(fp_line
			(start 0.3048 0.9906)
			(end 0.3048 -0.1016)
			(stroke
				(width 0.1)
				(type default)
			)
			(layer "F.Fab")
		)
		(fp_line
			(start -0.3048 0.9906)
			(end 0.3048 0.9906)
			(stroke
				(width 0.1)
				(type default)
			)
			(layer "F.Fab")
		)
		(pad "1" smd rect
			(at 0 0 90)
			(size 0.508 0.508)
			(layers "F.Cu" "F.Mask" "F.Paste")
			(net "P5V_STBY")
		)
		(pad "2" smd rect
			(at 0 0.889 90)
			(size 0.508 0.508)
			(layers "F.Cu" "F.Mask" "F.Paste")
			(net "GND")
		)
		(zone
			(layer "F.Cu")
			(hatch none 0.5)
			(connect_pads
				(clearance 0)
			)
			(min_thickness 0.25)
			(keepout
				(tracks not_allowed)
				(vias allowed)
				(pads allowed)
				(copperpour not_allowed)
				(footprints allowed)
			)
			(placement
				(enabled no)
				(sheetname "")
			)
			(fill
				(thermal_gap 0.5)
				(thermal_bridge_width 0.5)
				(island_removal_mode 0)
			)
			(polygon
				(pts
					(xy 198.75119 -61.372242) (xy 198.37019 -61.372242) (xy 198.37019 -60.864242) (xy 198.75119 -60.864242)
				)
			)
		)
		(zone
			(layer "F.Cu")
			(hatch none 0.5)
			(connect_pads
				(clearance 0)
			)
			(min_thickness 0.25)
			(keepout
				(tracks allowed)
				(vias not_allowed)
				(pads allowed)
				(copperpour not_allowed)
				(footprints allowed)
			)
			(placement
				(enabled no)
				(sheetname "")
			)
			(fill
				(thermal_gap 0.5)
				(thermal_bridge_width 0.5)
				(island_removal_mode 0)
			)
			(polygon
				(pts
					(xy 198.75119 -61.372242) (xy 198.37019 -61.372242) (xy 198.37019 -60.864242) (xy 198.75119 -60.864242)
				)
			)
		)
	)
)
